(kicad_pcb
	(version 20260206)
	(generator "pcbnew")
	(generator_version "10.0")
	(general
		(thickness 1.6)
		(legacy_teardrops no)
	)
	(paper "A4")
	(title_block
		(title "fcb — 12433-1M.1206WZS1330.brd")
		(comment 1 "Open Vault / Knox (Wiwynn) / footprints 35-41 of 495")
	)
	(layers
		(0 "F.Cu" signal "TOP")
		(4 "In1.Cu" signal "L2GND")
		(6 "In2.Cu" signal "L3VCC")
		(2 "B.Cu" signal "BOTTOM")
		(9 "F.Adhes" user "F.Adhesive")
		(11 "B.Adhes" user "B.Adhesive")
		(13 "F.Paste" user "Package Geometry/Pastemask Top")
		(15 "B.Paste" user "Package Geometry/Pastemask Bottom")
		(5 "F.SilkS" user "Ref Des/Silkscreen Top")
		(7 "B.SilkS" user "Ref Des/Silkscreen Bottom")
		(1 "F.Mask" user "Board Geometry/Soldermask Top")
		(3 "B.Mask" user "Board Geometry/Soldermask Bottom")
		(17 "Dwgs.User" user "User.Drawings")
		(19 "Cmts.User" user "User.Comments")
		(21 "Eco1.User" user "User.Eco1")
		(23 "Eco2.User" user "User.Eco2")
		(25 "Edge.Cuts" user "Board Geometry/Outline")
		(27 "Margin" user)
		(31 "F.CrtYd" user "Package Geometry/Place Bound Top")
		(29 "B.CrtYd" user "Package Geometry/Place Bound Bottom")
		(35 "F.Fab" user "Ref Des/Assembly Top")
		(33 "B.Fab" user "Ref Des/Assembly Bottom")
	)
	(footprint ""
		(layer "F.Cu")
		(at 18.7452 -250.5964 -90)
		(property "Reference" "PR53"
			(at 0 0 270)
			(layer "F.SilkS")
			(hide yes)
			(effects
				(font
					(size 1.27 1.27)
				)
			)
		)
		(property "Value" "10KR3J-L1-GP"
			(at -0.0254 -2.5146 270)
			(unlocked yes)
			(layer "F.Fab")
			(hide yes)
			(effects
				(font
					(size 1.016 1.016)
					(thickness 0.1524)
				)
			)
		)
		(property "Device Type" "R603H22"
			(at -0.0254 -4.0386 270)
			(unlocked yes)
			(layer "F.Fab")
			(hide yes)
			(effects
				(font
					(size 1.016 1.016)
					(thickness 0.1524)
				)
			)
		)
		(duplicate_pad_numbers_are_jumpers no)
		(fp_line
			(start -0.4826 0)
			(end -0.2032 0)
			(stroke
				(width 0.2032)
				(type default)
			)
			(layer "F.SilkS")
		)
		(fp_line
			(start 0.2032 0)
			(end 0.4826 0)
			(stroke
				(width 0.2032)
				(type default)
			)
			(layer "F.SilkS")
		)
		(fp_rect
			(start -0.5842 1.3335)
			(end 0.5842 -1.3335)
			(stroke
				(width 0)
				(type default)
			)
			(fill no)
			(layer "F.CrtYd")
		)
		(fp_rect
			(start -0.5842 1.3335)
			(end 0.5842 -1.3335)
			(stroke
				(width 0)
				(type default)
			)
			(fill no)
			(layer "F.Fab")
		)
		(pad "1" smd custom
			(at 0 -0.762 270)
			(size 0.2159 0.2159)
			(layers "F.Cu" "F.Mask" "F.Paste")
			(net "P3V3_EN")
			(options
				(clearance outline)
				(anchor circle)
			)
			(primitives
				(gr_poly
					(pts
						(arc
							(start -0.3302 -0.4318)
							(mid -0.402042 -0.402042)
							(end -0.4318 -0.3302)
						)
						(arc
							(start -0.4318 0.3302)
							(mid -0.402042 0.402042)
							(end -0.3302 0.4318)
						)
						(arc
							(start 0.3302 0.4318)
							(mid 0.402042 0.402042)
							(end 0.4318 0.3302)
						)
						(arc
							(start 0.4318 -0.3302)
							(mid 0.402042 -0.402042)
							(end 0.3302 -0.4318)
						)
					)
					(width 0)
					(fill yes)
				)
			)
		)
		(pad "2" smd custom
			(at 0 0.762 270)
			(size 0.2159 0.2159)
			(layers "F.Cu" "F.Mask" "F.Paste")
			(net "GND")
			(options
				(clearance outline)
				(anchor circle)
			)
			(primitives
				(gr_poly
					(pts
						(arc
							(start -0.3302 -0.4318)
							(mid -0.402042 -0.402042)
							(end -0.4318 -0.3302)
						)
						(arc
							(start -0.4318 0.3302)
							(mid -0.402042 0.402042)
							(end -0.3302 0.4318)
						)
						(arc
							(start 0.3302 0.4318)
							(mid 0.402042 0.402042)
							(end 0.4318 0.3302)
						)
						(arc
							(start 0.4318 -0.3302)
							(mid 0.402042 -0.402042)
							(end 0.3302 -0.4318)
						)
					)
					(width 0)
					(fill yes)
				)
			)
		)
	)
	(footprint ""
		(layer "F.Cu")
		(at 34.739834 -139.324334 90)
		(property "Reference" "TP24"
			(at 0 0 90)
			(layer "F.SilkS")
			(hide yes)
			(effects
				(font
					(size 1.27 1.27)
				)
			)
		)
		(property "Value" "TPAD32-GP"
			(at 0 -3.166364 90)
			(unlocked yes)
			(layer "F.Fab")
			(hide yes)
			(effects
				(font
					(size 1.016 1.016)
					(thickness 0.1524)
				)
			)
		)
		(property "Device Type" "TPAD32"
			(at 0 -4.690618 90)
			(unlocked yes)
			(layer "F.Fab")
			(hide yes)
			(effects
				(font
					(size 1.016 1.016)
					(thickness 0.1524)
				)
			)
		)
		(duplicate_pad_numbers_are_jumpers no)
		(fp_poly
			(pts
				(arc
					(start 0 0.7112)
					(mid 0 -0.7112)
					(end 0 0.7112)
				)
			)
			(stroke
				(width 0)
				(type default)
			)
			(fill no)
			(layer "F.CrtYd")
		)
		(fp_poly
			(pts
				(arc
					(start 0 0.7112)
					(mid 0 -0.7112)
					(end 0 0.7112)
				)
			)
			(stroke
				(width 0)
				(type default)
			)
			(fill no)
			(layer "F.Fab")
		)
		(pad "1" smd circle
			(at 0 0 90)
			(size 0.8128 0.8128)
			(layers "F.Cu" "F.Mask" "F.Paste")
			(net "P12VL_2490_PG")
		)
	)
	(footprint ""
		(layer "F.Cu")
		(at 43.8404 -394.1064 90)
		(property "Reference" "TC10"
			(at 0 0 90)
			(layer "F.SilkS")
			(hide yes)
			(effects
				(font
					(size 1.27 1.27)
				)
			)
		)
		(property "Value" "ST68U16VDM-1-GP"
			(at 0 -9.6012 90)
			(unlocked yes)
			(layer "F.Fab")
			(hide yes)
			(effects
				(font
					(size 1.016 1.016)
					(thickness 0.1524)
				)
			)
		)
		(property "Device Type" "CT7343H79"
			(at 0 -11.1252 90)
			(unlocked yes)
			(layer "F.Fab")
			(hide yes)
			(effects
				(font
					(size 1.016 1.016)
					(thickness 0.1524)
				)
			)
		)
		(duplicate_pad_numbers_are_jumpers no)
		(fp_line
			(start 2.286 -4.8768)
			(end -2.286 -4.8768)
			(stroke
				(width 0.1524)
				(type default)
			)
			(layer "F.SilkS")
		)
		(fp_line
			(start -2.286 -4.8768)
			(end -2.286 -2.032)
			(stroke
				(width 0.1524)
				(type default)
			)
			(layer "F.SilkS")
		)
		(fp_line
			(start 2.1082 -4.699)
			(end -2.1082 -4.699)
			(stroke
				(width 0.508)
				(type default)
			)
			(layer "F.SilkS")
		)
		(fp_line
			(start 2.286 -2.032)
			(end 2.286 -4.8768)
			(stroke
				(width 0.1524)
				(type default)
			)
			(layer "F.SilkS")
		)
		(fp_line
			(start 2.286 2.032)
			(end 2.286 4.8768)
			(stroke
				(width 0.1524)
				(type default)
			)
			(layer "F.SilkS")
		)
		(fp_line
			(start 2.286 4.8768)
			(end -2.286 4.8768)
			(stroke
				(width 0.1524)
				(type default)
			)
			(layer "F.SilkS")
		)
		(fp_line
			(start -2.286 4.8768)
			(end -2.286 2.032)
			(stroke
				(width 0.1524)
				(type default)
			)
			(layer "F.SilkS")
		)
		(fp_rect
			(start -2.1463 3.6449)
			(end 2.1463 -3.6449)
			(stroke
				(width 0)
				(type default)
			)
			(fill no)
			(layer "F.CrtYd")
		)
		(fp_poly
			(pts
				(xy -2.54 4.953) (xy -2.54 4.2926) (xy -3.81 4.2926) (xy -3.81 -4.2926) (xy -2.54 -4.2926) (xy -2.54 -4.953)
				(xy 2.54 -4.953) (xy 2.54 -4.2926) (xy 3.81 -4.2926) (xy 3.81 -1.6256) (xy 2.1463 -1.6256) (xy 2.1463 -3.6449)
				(xy -2.1463 -3.6449) (xy -2.1463 3.6449) (xy 2.1463 3.6449) (xy 2.1463 -1.6129) (xy 3.81 -1.6129)
				(xy 3.81 4.2926) (xy 2.54 4.2926) (xy 2.54 4.953)
			)
			(stroke
				(width 0)
				(type default)
			)
			(fill no)
			(layer "F.CrtYd")
		)
		(fp_rect
			(start 2.54 4.2926)
			(end 3.81 -4.2926)
			(stroke
				(width 0)
				(type default)
			)
			(fill no)
			(layer "F.Fab")
		)
		(fp_rect
			(start -3.81 4.2926)
			(end -2.54 -4.2926)
			(stroke
				(width 0)
				(type default)
			)
			(fill no)
			(layer "F.Fab")
		)
		(fp_rect
			(start -2.54 4.953)
			(end 2.54 -4.953)
			(stroke
				(width 0)
				(type default)
			)
			(fill no)
			(layer "F.Fab")
		)
		(pad "1" smd rect
			(at 0 -3.1496 90)
			(size 2.413 2.286)
			(layers "F.Cu" "F.Mask" "F.Paste")
			(net "P12V")
		)
		(pad "2" smd rect
			(at 0 3.1496 90)
			(size 2.413 2.286)
			(layers "F.Cu" "F.Mask" "F.Paste")
			(net "GND")
		)
		(zone
			(layer "F.Cu")
			(hatch none 0.5)
			(connect_pads
				(clearance 0)
			)
			(min_thickness 0.25)
			(keepout
				(tracks allowed)
				(vias not_allowed)
				(pads allowed)
				(copperpour not_allowed)
				(footprints allowed)
			)
			(placement
				(enabled no)
				(sheetname "")
			)
			(fill
				(thermal_gap 0.5)
				(thermal_bridge_width 0.5)
				(island_removal_mode 0)
			)
			(polygon
				(pts
					(xy 42.1513 -395.6177) (xy 39.243 -395.6177) (xy 39.243 -392.5951) (xy 42.1386 -392.5951) (xy 42.4688 -392.5951)
					(xy 42.4688 -395.6177)
				)
			)
		)
		(zone
			(layer "F.Cu")
			(hatch none 0.5)
			(connect_pads
				(clearance 0)
			)
			(min_thickness 0.25)
			(keepout
				(tracks allowed)
				(vias not_allowed)
				(pads allowed)
				(copperpour not_allowed)
				(footprints allowed)
			)
			(placement
				(enabled no)
				(sheetname "")
			)
			(fill
				(thermal_gap 0.5)
				(thermal_bridge_width 0.5)
				(island_removal_mode 0)
			)
			(polygon
				(pts
					(xy 48.4378 -392.5951) (xy 48.4378 -395.6177) (xy 45.5422 -395.6177) (xy 45.212 -395.6177) (xy 45.212 -392.5951)
					(xy 45.5422 -392.5951)
				)
			)
		)
	)
	(footprint ""
		(layer "F.Cu")
		(at 45.466 -179.451)
		(property "Reference" "TP21"
			(at 0 0 0)
			(layer "F.SilkS")
			(hide yes)
			(effects
				(font
					(size 1.27 1.27)
				)
			)
		)
		(property "Value" "TPAD32-GP"
			(at 0 -3.166364 0)
			(unlocked yes)
			(layer "F.Fab")
			(hide yes)
			(effects
				(font
					(size 1.016 1.016)
					(thickness 0.1524)
				)
			)
		)
		(property "Device Type" "TPAD32"
			(at 0 -4.690618 0)
			(unlocked yes)
			(layer "F.Fab")
			(hide yes)
			(effects
				(font
					(size 1.016 1.016)
					(thickness 0.1524)
				)
			)
		)
		(duplicate_pad_numbers_are_jumpers no)
		(fp_poly
			(pts
				(arc
					(start 0.7112 0)
					(mid -0.7112 0)
					(end 0.7112 0)
				)
			)
			(stroke
				(width 0)
				(type default)
			)
			(fill no)
			(layer "F.CrtYd")
		)
		(fp_poly
			(pts
				(arc
					(start 0.7112 0)
					(mid -0.7112 0)
					(end 0.7112 0)
				)
			)
			(stroke
				(width 0)
				(type default)
			)
			(fill no)
			(layer "F.Fab")
		)
		(pad "1" smd circle
			(at 0 0)
			(size 0.8128 0.8128)
			(layers "F.Cu" "F.Mask" "F.Paste")
			(net "D_LATCH_Q#")
		)
	)
	(footprint ""
		(layer "F.Cu")
		(at 10.5664 -447.2686)
		(property "Reference" "D12"
			(at 0 0 0)
			(layer "F.SilkS")
			(hide yes)
			(effects
				(font
					(size 1.27 1.27)
				)
			)
		)
		(property "Value" "BAS16H-GP"
			(at 0 -5.5372 0)
			(unlocked yes)
			(layer "F.Fab")
			(hide yes)
			(effects
				(font
					(size 1.016 1.016)
					(thickness 0.1524)
				)
			)
		)
		(property "Device Type" "SOD123AKH48"
			(at 0 -7.0612 0)
			(unlocked yes)
			(layer "F.Fab")
			(hide yes)
			(effects
				(font
					(size 1.016 1.016)
					(thickness 0.1524)
				)
			)
		)
		(duplicate_pad_numbers_are_jumpers no)
		(fp_line
			(start -1.016 -2.667)
			(end -1.016 2.667)
			(stroke
				(width 0.1524)
				(type default)
			)
			(layer "F.SilkS")
		)
		(fp_line
			(start -1.016 2.667)
			(end 1.016 2.667)
			(stroke
				(width 0.1524)
				(type default)
			)
			(layer "F.SilkS")
		)
		(fp_line
			(start 0.889 2.921)
			(end -0.889 2.921)
			(stroke
				(width 0.508)
				(type default)
			)
			(layer "F.SilkS")
		)
		(fp_line
			(start 1.016 -2.667)
			(end -1.016 -2.667)
			(stroke
				(width 0.1524)
				(type default)
			)
			(layer "F.SilkS")
		)
		(fp_line
			(start 1.016 2.667)
			(end 1.016 -2.667)
			(stroke
				(width 0.1524)
				(type default)
			)
			(layer "F.SilkS")
		)
		(fp_rect
			(start -1.143 3.175)
			(end 1.143 -2.794)
			(stroke
				(width 0)
				(type default)
			)
			(fill no)
			(layer "F.CrtYd")
		)
		(fp_poly
			(pts
				(xy -1.143 -2.794) (xy 1.143 -2.794) (xy 1.143 3.175) (xy -1.143 3.175)
			)
			(stroke
				(width 0)
				(type default)
			)
			(fill no)
			(layer "F.Fab")
		)
		(pad "A" smd rect
			(at 0 -1.6891)
			(size 0.889 1.397)
			(layers "F.Cu" "F.Mask" "F.Paste")
			(net "FAN_TACH2")
		)
		(pad "K" smd rect
			(at 0 1.6891)
			(size 0.889 1.397)
			(layers "F.Cu" "F.Mask" "F.Paste")
			(net "P12V")
		)
	)
	(footprint ""
		(layer "F.Cu")
		(at 14.5034 -248.1834)
		(property "Reference" "PR57"
			(at 0 0 0)
			(layer "F.SilkS")
			(hide yes)
			(effects
				(font
					(size 1.27 1.27)
				)
			)
		)
		(property "Value" "0R0603-PAD-2-GP"
			(at -0.0254 -2.3622 0)
			(unlocked yes)
			(layer "F.Fab")
			(hide yes)
			(effects
				(font
					(size 1.016 1.016)
					(thickness 0.1524)
				)
			)
		)
		(property "Device Type" "0R0603-PAD-1"
			(at -0.0254 -3.8862 0)
			(unlocked yes)
			(layer "F.Fab")
			(hide yes)
			(effects
				(font
					(size 1.016 1.016)
					(thickness 0.1524)
				)
			)
		)
		(duplicate_pad_numbers_are_jumpers no)
		(fp_line
			(start -0.6604 -1.3716)
			(end -0.6604 1.3716)
			(stroke
				(width 0.1524)
				(type default)
			)
			(layer "F.SilkS")
		)
		(fp_line
			(start 0.6604 -1.3716)
			(end -0.6604 -1.3716)
			(stroke
				(width 0.1524)
				(type default)
			)
			(layer "F.SilkS")
		)
		(fp_rect
			(start -0.6604 1.3716)
			(end 0.6604 -1.3716)
			(stroke
				(width 0)
				(type default)
			)
			(fill no)
			(layer "F.CrtYd")
		)
		(fp_rect
			(start -0.6604 1.3716)
			(end 0.6604 -1.3716)
			(stroke
				(width 0)
				(type default)
			)
			(fill no)
			(layer "F.Fab")
		)
		(pad "1" smd custom
			(at 0 -0.8509)
			(size 0.2159 0.2159)
			(layers "F.Cu" "F.Mask" "F.Paste")
			(net "P12V")
			(options
				(clearance outline)
				(anchor circle)
			)
			(primitives
				(gr_poly
					(pts
						(arc
							(start 0.4318 0.4826)
							(mid 0.402042 0.554442)
							(end 0.3302 0.5842)
						)
						(arc
							(start -0.3302 0.5842)
							(mid -0.402042 0.554442)
							(end -0.4318 0.4826)
						)
						(arc
							(start -0.4318 -0.4826)
							(mid -0.402042 -0.554442)
							(end -0.3302 -0.5842)
						)
						(arc
							(start 0.3302 -0.5842)
							(mid 0.402042 -0.554442)
							(end 0.4318 -0.4826)
						)
					)
					(width 0)
					(fill yes)
				)
			)
		)
		(pad "2" smd custom
			(at 0 0.6731)
			(size 0.2159 0.2159)
			(layers "F.Cu" "F.Mask" "F.Paste")
			(net "P3V3_IN")
			(options
				(clearance outline)
				(anchor circle)
			)
			(primitives
				(gr_poly
					(pts
						(arc
							(start -0.3302 0.5842)
							(mid -0.402042 0.554442)
							(end -0.4318 0.4826)
						)
						(arc
							(start -0.4318 -0.4826)
							(mid -0.402042 -0.554442)
							(end -0.3302 -0.5842)
						)
						(arc
							(start 0.3302 -0.5842)
							(mid 0.402042 -0.554442)
							(end 0.4318 -0.4826)
						)
						(arc
							(start 0.4318 0.4826)
							(mid 0.402042 0.554442)
							(end 0.3302 0.5842)
						)
					)
					(width 0)
					(fill yes)
				)
			)
		)
	)
	(footprint ""
		(layer "F.Cu")
		(at 4.040124 -193.339974 -90)
		(property "Reference" "CN4"
			(at 0 0 270)
			(layer "F.SilkS")
			(hide yes)
			(effects
				(font
					(size 1.27 1.27)
				)
			)
		)
		(property "Value" "JWT-CON5-42-GP"
			(at -7.8105 2.9591 270)
			(unlocked yes)
			(layer "F.Fab")
			(hide yes)
			(effects
				(font
					(size 1.016 1.016)
					(thickness 0.1524)
				)
			)
		)
		(property "Device Type" "A2541WR0-1TX5PA-6T-0E"
			(at -7.8105 1.4351 270)
			(unlocked yes)
			(layer "F.Fab")
			(hide yes)
			(effects
				(font
					(size 1.016 1.016)
					(thickness 0.1524)
				)
			)
		)
		(duplicate_pad_numbers_are_jumpers no)
		(fp_line
			(start -6.604 10.287)
			(end 6.604 10.287)
			(stroke
				(width 0.1524)
				(type default)
			)
			(layer "F.SilkS")
		)
		(fp_line
			(start 6.604 10.287)
			(end 6.604 -0.9652)
			(stroke
				(width 0.1524)
				(type default)
			)
			(layer "F.SilkS")
		)
		(fp_line
			(start -6.604 -0.9652)
			(end -6.604 10.287)
			(stroke
				(width 0.1524)
				(type default)
			)
			(layer "F.SilkS")
		)
		(fp_line
			(start 6.604 -0.9652)
			(end -6.604 -0.9652)
			(stroke
				(width 0.1524)
				(type default)
			)
			(layer "F.SilkS")
		)
		(fp_line
			(start -6.731 -1.0922)
			(end -6.731 0.1778)
			(stroke
				(width 0.4064)
				(type default)
			)
			(layer "F.SilkS")
		)
		(fp_line
			(start -5.461 -1.0922)
			(end -6.731 -1.0922)
			(stroke
				(width 0.4064)
				(type default)
			)
			(layer "F.SilkS")
		)
		(fp_circle
			(center -5.08 0)
			(end -5.08 -1.0668)
			(stroke
				(width 0.3048)
				(type default)
			)
			(fill no)
			(layer "F.SilkS")
		)
		(fp_circle
			(center -2.54 0)
			(end -2.54 -1.0668)
			(stroke
				(width 0.3048)
				(type default)
			)
			(fill no)
			(layer "F.SilkS")
		)
		(fp_circle
			(center 0 0)
			(end 0 -1.0668)
			(stroke
				(width 0.3048)
				(type default)
			)
			(fill no)
			(layer "F.SilkS")
		)
		(fp_circle
			(center 2.54 0)
			(end 2.54 -1.0668)
			(stroke
				(width 0.3048)
				(type default)
			)
			(fill no)
			(layer "F.SilkS")
		)
		(fp_circle
			(center 5.08 0)
			(end 5.08 -1.0668)
			(stroke
				(width 0.3048)
				(type default)
			)
			(fill no)
			(layer "F.SilkS")
		)
		(fp_rect
			(start -6.35 10.033)
			(end 6.35 -0.3302)
			(stroke
				(width 0)
				(type default)
			)
			(fill no)
			(layer "F.CrtYd")
		)
		(fp_poly
			(pts
				(xy -6.35 -0.3302) (xy 6.858 -0.3302) (xy 6.858 -1.2192) (xy -6.858 -1.2192) (xy -6.858 10.541)
				(xy 6.858 10.541) (xy 6.858 -0.3175) (xy 6.35 -0.3175) (xy 6.35 10.033) (xy -6.35 10.033)
			)
			(stroke
				(width 0)
				(type default)
			)
			(fill no)
			(layer "F.CrtYd")
		)
		(fp_rect
			(start -6.858 10.541)
			(end 6.858 -1.2192)
			(stroke
				(width 0)
				(type default)
			)
			(fill no)
			(layer "F.Fab")
		)
		(pad "1" thru_hole circle
			(at -5.08 0 270)
			(size 1.4224 1.4224)
			(drill 1.016)
			(layers "*.Cu" "*.Mask")
			(remove_unused_layers no)
			(net "GND")
			(clearance 0.1524)
			(thermal_gap 0.1524)
		)
		(pad "2" thru_hole circle
			(at -2.54 0 270)
			(size 1.4224 1.4224)
			(drill 1.016)
			(layers "*.Cu" "*.Mask")
			(remove_unused_layers no)
			(net "P12V_FAN4")
			(clearance 0.1524)
			(thermal_gap 0.1524)
		)
		(pad "3" thru_hole circle
			(at 0 0 270)
			(size 1.4224 1.4224)
			(drill 1.016)
			(layers "*.Cu" "*.Mask")
			(remove_unused_layers no)
			(net "FAN_TACH8")
			(clearance 0.1524)
			(thermal_gap 0.1524)
		)
		(pad "4" thru_hole circle
			(at 2.54 0 270)
			(size 1.4224 1.4224)
			(drill 1.016)
			(layers "*.Cu" "*.Mask")
			(remove_unused_layers no)
			(net "PWM_OUT_FAN4_NET")
			(clearance 0.1524)
			(thermal_gap 0.1524)
		)
		(pad "5" thru_hole circle
			(at 5.08 0 270)
			(size 1.4224 1.4224)
			(drill 1.016)
			(layers "*.Cu" "*.Mask")
			(remove_unused_layers no)
			(net "FAN_TACH7")
			(clearance 0.1524)
			(thermal_gap 0.1524)
		)
	)
)
